#ISCELL
  mstr_misc dns *
  *
#ISCELL
  mstr_symbols design_note *
  *
#ISCELL
  mstr_symbols intel_corp_bpage *
  *
#ISCELL
  mstr_standard offpage *
  page223_i1
#ISCELL
  mstr_standard offpage *
  page223_i10
#ISCELL
  mstr_standard offpage *
  page223_i11
#CELL
  mstr_discrete res *
  page223_i13
#CELL
  mstr_discrete res *
  page223_i14
#ISCELL
  mstr_symbols p3v3_stby *
  page223_i15
#CELL
  mstr_discrete res *
  page223_i16
#CELL
  mstr_discrete res *
  page223_i17
#ISCELL
  mstr_standard offpage *
  page223_i18
#ISCELL
  mstr_standard offpage *
  page223_i19
#ISCELL
  mstr_standard offpage *
  page223_i2
#ISCELL
  mstr_standard offpage *
  page223_i20
#CELL
  mstr_discrete res *
  page223_i21
#CELL
  mstr_discrete res *
  page223_i22
#CELL
  mstr_discrete res *
  page223_i23
#ISCELL
  mstr_symbols gnd *
  page223_i24
#CELL
  dev_discrete cap_a *
  page223_i25
#ISCELL
  mstr_symbols gnd *
  page223_i26
#CELL
  dev_discrete cap_a *
  page223_i27
#ISCELL
  mstr_symbols gnd *
  page223_i28
#ISCELL
  mstr_symbols p3v3_stby *
  page223_i29
#CELL
  mstr_discrete res *
  page223_i30
#CELL
  mstr_discrete res *
  page223_i32
#ISCELL
  mstr_standard offpage *
  page223_i34
#ISCELL
  mstr_symbols gnd *
  page223_i35
#CELL
  mstr_discrete cap *
  page223_i36
#CELL
  mstr_discrete cap *
  page223_i39
#ISCELL
  mstr_standard offpage *
  page223_i4
#ISCELL
  mstr_standard offpage *
  page223_i40
#CELL
  dev_discrete cap_a *
  page223_i41
#ISCELL
  mstr_symbols gnd *
  page223_i42
#ISCELL
  mstr_symbols gnd *
  page223_i43
#CELL
  dev_discrete cap_a *
  page223_i44
#ISCELL
  mstr_standard offpage *
  page223_i45
#ISCELL
  mstr_symbols gnd *
  page223_i46
#ISCELL
  mstr_symbols gnd *
  page223_i47
#ISCELL
  mstr_symbols gnd *
  page223_i48
#ISCELL
  mstr_symbols pvccio_cpu1 *
  page223_i49
#CELL
  mstr_discrete res *
  page223_i50
#CELL
  mstr_discrete res *
  page223_i53
#ISCELL
  mstr_symbols vcc_core *
  page223_i56
#CELL
  mstr_discrete res *
  page223_i57
#CELL
  mstr_discrete res *
  page223_i58
#CELL
  mstr_discrete cap *
  page223_i59
#ISCELL
  mstr_symbols gnd *
  page223_i60
#ISCELL
  mstr_symbols gnd *
  page223_i61
#ISCELL
  mstr_standard offpage *
  page223_i62
#ISCELL
  mstr_standard offpage *
  page223_i63
#ISCELL
  mstr_standard offpage *
  page223_i64
#ISCELL
  mstr_standard offpage *
  page223_i65
#ISCELL
  mstr_standard offpage *
  page223_i67
#ISCELL
  mstr_standard offpage *
  page223_i68
#ISCELL
  mstr_symbols pvccio_cpu1 *
  page223_i7
#ISCELL
  mstr_standard offpage *
  page223_i70
#ISCELL
  mstr_standard offpage *
  page223_i71
#ISCELL
  mstr_standard offpage *
  page223_i72
#ISCELL
  mstr_standard offpage *
  page223_i74
#CELL
  mstr_discrete res *
  page223_i77
#CELL
  mstr_discrete res *
  page223_i78
#CELL
  mstr_discrete res *
  page223_i79
#CELL
  mstr_discrete res *
  page223_i8
#CELL
  mstr_discrete cap *
  page223_i80
#ISCELL
  mstr_symbols gnd *
  page223_i81
#CELL
  mstr_discrete res *
  page223_i82
#CELL
  mstr_discrete res *
  page223_i84
#CELL
  mstr_discrete res *
  page223_i85
#CELL
  mstr_discrete res *
  page223_i87
#CELL
  mstr_discrete res *
  page223_i88
#ISCELL
  mstr_standard offpage *
  page223_i89
#ISCELL
  mstr_standard offpage *
  page223_i9
#CELL
  mstr_controller pxm1310b *
  page223_i90
#ISCELL
  mstr_symbols gnd *
  page223_i91
#CELL
  dev_discrete cap_a *
  page223_i92
